(kicad_pcb
	(version 20260206)
	(generator "pcbnew")
	(generator_version "10.0")
	(general
		(thickness 1.6)
		(legacy_teardrops no)
	)
	(paper "A4")
	(title_block
		(title "netronome-mezz — pcbd0082-001_rev01_jul9_a.brd")
		(comment 1 "Open CloudServer (Microsoft) / footprints 53-60 of 714")
	)
	(layers
		(0 "F.Cu" signal "TOP")
		(4 "In1.Cu" signal "02_GND")
		(6 "In2.Cu" signal "03_SIG")
		(8 "In3.Cu" signal "04_SIG")
		(10 "In4.Cu" signal "05_GND")
		(12 "In5.Cu" signal "06_PWR1")
		(14 "In6.Cu" signal "07_SIG")
		(16 "In7.Cu" signal "08_SIG")
		(18 "In8.Cu" signal "09_GND")
		(2 "B.Cu" signal "BOTTOM")
		(9 "F.Adhes" user "F.Adhesive")
		(11 "B.Adhes" user "B.Adhesive")
		(13 "F.Paste" user "Package Geometry/Pastemask Top")
		(15 "B.Paste" user "Package Geometry/Pastemask Bottom")
		(5 "F.SilkS" user "Ref Des/Silkscreen Top")
		(7 "B.SilkS" user "Ref Des/Silkscreen Bottom")
		(1 "F.Mask" user "Board Geometry/Soldermask Top")
		(3 "B.Mask" user "Board Geometry/Soldermask Bottom")
		(17 "Dwgs.User" user "User.Drawings")
		(19 "Cmts.User" user "User.Comments")
		(21 "Eco1.User" user "User.Eco1")
		(23 "Eco2.User" user "User.Eco2")
		(25 "Edge.Cuts" user "Board Geometry/Outline")
		(27 "Margin" user)
		(31 "F.CrtYd" user "Package Geometry/Place Bound Top")
		(29 "B.CrtYd" user "Package Geometry/Place Bound Bottom")
		(35 "F.Fab" user "Ref Des/Assembly Top")
		(33 "B.Fab" user "Ref Des/Assembly Bottom")
		(45 "User.4" user "COMPVAL_TYPE_BOTTOM")
	)
	(footprint ""
		(layer "F.Cu")
		(at 78.359 26.924)
		(property "Reference" "R225"
			(at 0 0 0)
			(layer "F.SilkS")
			(hide yes)
			(effects
				(font
					(size 1.27 1.27)
				)
			)
		)
		(property "Value" "39.0"
			(at -0.148158 1.3462 90)
			(unlocked yes)
			(layer "F.Fab")
			(hide yes)
			(effects
				(font
					(size 1.27 0.9652)
					(thickness 0.000001)
				)
				(justify left)
			)
		)
		(property "Device Type" "REST0108"
			(at -0.148158 1.3462 90)
			(unlocked yes)
			(layer "F.Fab")
			(hide yes)
			(effects
				(font
					(size 1.27 0.9652)
					(thickness 0.000001)
				)
				(justify left)
			)
		)
		(duplicate_pad_numbers_are_jumpers no)
		(fp_poly
			(pts
				(xy 0.635 1.0668) (xy 0.635 -1.0668) (xy -0.635 -1.0668) (xy -0.635 1.0668)
			)
			(stroke
				(width 0)
				(type default)
			)
			(fill no)
			(layer "F.CrtYd")
		)
		(fp_line
			(start -0.254 -0.508)
			(end 0.254 -0.508)
			(stroke
				(width 0.0254)
				(type default)
			)
			(layer "F.Fab")
		)
		(fp_line
			(start -0.254 0.508)
			(end -0.254 -0.508)
			(stroke
				(width 0.0254)
				(type default)
			)
			(layer "F.Fab")
		)
		(fp_line
			(start 0.254 -0.508)
			(end 0.254 0.508)
			(stroke
				(width 0.0254)
				(type default)
			)
			(layer "F.Fab")
		)
		(fp_line
			(start 0.254 0.508)
			(end -0.254 0.508)
			(stroke
				(width 0.0254)
				(type default)
			)
			(layer "F.Fab")
		)
		(pad "1" smd rect
			(at 0 -0.4191)
			(size 0.508 0.5334)
			(layers "F.Cu" "F.Mask" "F.Paste")
			(net "DDR0_32A_RAS_L")
		)
		(pad "2" smd rect
			(at 0 0.4191)
			(size 0.508 0.5334)
			(layers "F.Cu" "F.Mask" "F.Paste")
			(net "DDR_VTT")
		)
		(zone
			(layer "F.Cu")
			(hatch none 0.5)
			(connect_pads
				(clearance 0)
			)
			(min_thickness 0.25)
			(keepout
				(tracks not_allowed)
				(vias allowed)
				(pads allowed)
				(copperpour not_allowed)
				(footprints allowed)
			)
			(placement
				(enabled no)
				(sheetname "")
			)
			(fill
				(thermal_gap 0.5)
				(thermal_bridge_width 0.5)
				(island_removal_mode 0)
			)
			(polygon
				(pts
					(xy 78.3844 26.8986) (xy 78.3844 26.9494) (xy 78.3336 26.9494) (xy 78.3336 26.8986)
				)
			)
		)
	)
	(footprint ""
		(layer "F.Cu")
		(at 39.243 37.4015 90)
		(property "Reference" "C143"
			(at -0.47117 2.032 0)
			(unlocked yes)
			(layer "F.SilkS")
			(effects
				(font
					(size 0.7874 0.5842)
					(thickness 0.127)
				)
				(justify left)
			)
		)
		(property "Value" "4.7UF"
			(at -0.783158 2.3876 180)
			(unlocked yes)
			(layer "F.Fab")
			(hide yes)
			(effects
				(font
					(size 1.27 0.9652)
					(thickness 0.000001)
				)
				(justify left)
			)
		)
		(property "Device Type" "CAPC0029"
			(at -0.783158 2.3876 180)
			(unlocked yes)
			(layer "F.Fab")
			(hide yes)
			(effects
				(font
					(size 1.27 0.9652)
					(thickness 0.000001)
				)
				(justify left)
			)
		)
		(duplicate_pad_numbers_are_jumpers no)
		(fp_arc
			(start 0.156058 -0.0889)
			(mid 0.173617 -0.045983)
			(end 0.179603 0)
			(stroke
				(width 0.2032)
				(type default)
			)
			(layer "F.SilkS")
		)
		(fp_arc
			(start 0.179603 0)
			(mid 0.173617 0.045983)
			(end 0.156058 0.0889)
			(stroke
				(width 0.2032)
				(type default)
			)
			(layer "F.SilkS")
		)
		(fp_arc
			(start -0.179603 0)
			(mid -0.173617 -0.045983)
			(end -0.156058 -0.0889)
			(stroke
				(width 0.2032)
				(type default)
			)
			(layer "F.SilkS")
		)
		(fp_arc
			(start -0.156058 0.0889)
			(mid -0.173617 0.045983)
			(end -0.179603 0)
			(stroke
				(width 0.2032)
				(type default)
			)
			(layer "F.SilkS")
		)
		(fp_circle
			(center 0 0)
			(end 0 0.179603)
			(stroke
				(width 0.2032)
				(type default)
			)
			(fill no)
			(layer "F.SilkS")
		)
		(fp_poly
			(pts
				(xy -1.2192 2.3495) (xy 1.2192 2.3495) (xy 1.2192 -2.3495) (xy -1.2192 -2.3495)
			)
			(stroke
				(width 0)
				(type default)
			)
			(fill no)
			(layer "F.CrtYd")
		)
		(fp_line
			(start 0.762 -1.143)
			(end 0.762 1.143)
			(stroke
				(width 0.0254)
				(type default)
			)
			(layer "F.Fab")
		)
		(fp_line
			(start -0.762 -1.143)
			(end 0.762 -1.143)
			(stroke
				(width 0.0254)
				(type default)
			)
			(layer "F.Fab")
		)
		(fp_line
			(start 0.762 1.143)
			(end -0.762 1.143)
			(stroke
				(width 0.0254)
				(type default)
			)
			(layer "F.Fab")
		)
		(fp_line
			(start -0.762 1.143)
			(end -0.762 -1.143)
			(stroke
				(width 0.0254)
				(type default)
			)
			(layer "F.Fab")
		)
		(pad "1" smd rect
			(at 0 -1.143 90)
			(size 1.4224 1.397)
			(layers "F.Cu" "F.Mask" "F.Paste")
			(net "10N2370")
		)
		(pad "2" smd rect
			(at 0 1.143 90)
			(size 1.4224 1.397)
			(layers "F.Cu" "F.Mask" "F.Paste")
			(net "GND")
		)
		(zone
			(layer "F.Cu")
			(hatch none 0.5)
			(connect_pads
				(clearance 0)
			)
			(min_thickness 0.25)
			(keepout
				(tracks allowed)
				(vias not_allowed)
				(pads allowed)
				(copperpour not_allowed)
				(footprints allowed)
			)
			(placement
				(enabled no)
				(sheetname "")
			)
			(fill
				(thermal_gap 0.5)
				(thermal_bridge_width 0.5)
				(island_removal_mode 0)
			)
			(polygon
				(pts
					(xy 38.862 38.0365) (xy 38.862 36.7665) (xy 39.624 36.7665) (xy 39.624 38.0365)
				)
			)
		)
	)
	(footprint ""
		(layer "F.Cu")
		(at 59.3725 46.609)
		(property "Reference" "R411"
			(at -0.67183 0.508 90)
			(unlocked yes)
			(layer "F.SilkS")
			(effects
				(font
					(size 0.7874 0.5842)
					(thickness 0.127)
				)
				(justify left)
			)
		)
		(property "Value" "1.0K"
			(at -0.148158 1.3462 90)
			(unlocked yes)
			(layer "F.Fab")
			(hide yes)
			(effects
				(font
					(size 1.27 0.9652)
					(thickness 0.000001)
				)
				(justify left)
			)
		)
		(property "Device Type" "REST0025"
			(at -0.148158 1.3462 90)
			(unlocked yes)
			(layer "F.Fab")
			(hide yes)
			(effects
				(font
					(size 1.27 0.9652)
					(thickness 0.000001)
				)
				(justify left)
			)
		)
		(duplicate_pad_numbers_are_jumpers no)
		(fp_poly
			(pts
				(xy 0.635 1.0668) (xy 0.635 -1.0668) (xy -0.635 -1.0668) (xy -0.635 1.0668)
			)
			(stroke
				(width 0)
				(type default)
			)
			(fill no)
			(layer "F.CrtYd")
		)
		(fp_line
			(start -0.254 -0.508)
			(end 0.254 -0.508)
			(stroke
				(width 0.0254)
				(type default)
			)
			(layer "F.Fab")
		)
		(fp_line
			(start -0.254 0.508)
			(end -0.254 -0.508)
			(stroke
				(width 0.0254)
				(type default)
			)
			(layer "F.Fab")
		)
		(fp_line
			(start 0.254 -0.508)
			(end 0.254 0.508)
			(stroke
				(width 0.0254)
				(type default)
			)
			(layer "F.Fab")
		)
		(fp_line
			(start 0.254 0.508)
			(end -0.254 0.508)
			(stroke
				(width 0.0254)
				(type default)
			)
			(layer "F.Fab")
		)
		(pad "1" smd rect
			(at 0 -0.4191)
			(size 0.508 0.5334)
			(layers "F.Cu" "F.Mask" "F.Paste")
			(net "GND")
		)
		(pad "2" smd rect
			(at 0 0.4191)
			(size 0.508 0.5334)
			(layers "F.Cu" "F.Mask" "F.Paste")
			(net "VDD_5.0V")
		)
		(zone
			(layer "F.Cu")
			(hatch none 0.5)
			(connect_pads
				(clearance 0)
			)
			(min_thickness 0.25)
			(keepout
				(tracks not_allowed)
				(vias allowed)
				(pads allowed)
				(copperpour not_allowed)
				(footprints allowed)
			)
			(placement
				(enabled no)
				(sheetname "")
			)
			(fill
				(thermal_gap 0.5)
				(thermal_bridge_width 0.5)
				(island_removal_mode 0)
			)
			(polygon
				(pts
					(xy 59.3979 46.5836) (xy 59.3979 46.6344) (xy 59.3471 46.6344) (xy 59.3471 46.5836)
				)
			)
		)
	)
	(footprint ""
		(layer "F.Cu")
		(at 83.82 50.419 90)
		(property "Reference" "C130"
			(at -0.02667 0.889 0)
			(unlocked yes)
			(layer "F.SilkS")
			(effects
				(font
					(size 0.7874 0.5842)
					(thickness 0.127)
				)
				(justify left)
			)
		)
		(property "Value" "0.1UF"
			(at -0.091846 0.2921 180)
			(unlocked yes)
			(layer "F.Fab")
			(hide yes)
			(effects
				(font
					(size 0.7874 0.5842)
					(thickness 0.2032)
				)
				(justify left)
			)
		)
		(property "Device Type" "CAPC0073"
			(at -0.091846 0.2921 180)
			(unlocked yes)
			(layer "F.Fab")
			(hide yes)
			(effects
				(font
					(size 0.7874 0.5842)
					(thickness 0.2032)
				)
				(justify left)
			)
		)
		(duplicate_pad_numbers_are_jumpers no)
		(fp_poly
			(pts
				(xy 0.635 1.0668) (xy 0.635 -1.0668) (xy -0.635 -1.0668) (xy -0.635 1.0668)
			)
			(stroke
				(width 0)
				(type default)
			)
			(fill no)
			(layer "F.CrtYd")
		)
		(fp_line
			(start 0.254 -0.508)
			(end 0.254 0.508)
			(stroke
				(width 0.0254)
				(type default)
			)
			(layer "F.Fab")
		)
		(fp_line
			(start -0.254 -0.508)
			(end 0.254 -0.508)
			(stroke
				(width 0.0254)
				(type default)
			)
			(layer "F.Fab")
		)
		(fp_line
			(start 0.254 0.508)
			(end -0.254 0.508)
			(stroke
				(width 0.0254)
				(type default)
			)
			(layer "F.Fab")
		)
		(fp_line
			(start -0.254 0.508)
			(end -0.254 -0.508)
			(stroke
				(width 0.0254)
				(type default)
			)
			(layer "F.Fab")
		)
		(pad "1" smd rect
			(at 0 -0.4191 90)
			(size 0.508 0.5334)
			(layers "F.Cu" "F.Mask" "F.Paste")
			(net "EXT_12.0V")
		)
		(pad "2" smd rect
			(at 0 0.4191 90)
			(size 0.508 0.5334)
			(layers "F.Cu" "F.Mask" "F.Paste")
			(net "GND")
		)
		(zone
			(layer "F.Cu")
			(hatch none 0.5)
			(connect_pads
				(clearance 0)
			)
			(min_thickness 0.25)
			(keepout
				(tracks not_allowed)
				(vias allowed)
				(pads allowed)
				(copperpour not_allowed)
				(footprints allowed)
			)
			(placement
				(enabled no)
				(sheetname "")
			)
			(fill
				(thermal_gap 0.5)
				(thermal_bridge_width 0.5)
				(island_removal_mode 0)
			)
			(polygon
				(pts
					(xy 83.7946 50.3936) (xy 83.8454 50.3936) (xy 83.8454 50.4444) (xy 83.7946 50.4444)
				)
			)
		)
	)
	(footprint ""
		(layer "F.Cu")
		(at 25.9588 35.941 -90)
		(property "Reference" "R86"
			(at 0 0 270)
			(layer "F.SilkS")
			(hide yes)
			(effects
				(font
					(size 1.27 1.27)
				)
			)
		)
		(property "Value" "4.75K"
			(at -0.148158 1.3462 0)
			(unlocked yes)
			(layer "F.Fab")
			(hide yes)
			(effects
				(font
					(size 1.27 0.9652)
					(thickness 0.000001)
				)
				(justify left)
			)
		)
		(property "Device Type" "REST4024"
			(at -0.148158 1.3462 0)
			(unlocked yes)
			(layer "F.Fab")
			(hide yes)
			(effects
				(font
					(size 1.27 0.9652)
					(thickness 0.000001)
				)
				(justify left)
			)
		)
		(duplicate_pad_numbers_are_jumpers no)
		(fp_poly
			(pts
				(xy 0.635 1.0668) (xy 0.635 -1.0668) (xy -0.635 -1.0668) (xy -0.635 1.0668)
			)
			(stroke
				(width 0)
				(type default)
			)
			(fill no)
			(layer "F.CrtYd")
		)
		(fp_line
			(start -0.254 0.508)
			(end -0.254 -0.508)
			(stroke
				(width 0.0254)
				(type default)
			)
			(layer "F.Fab")
		)
		(fp_line
			(start 0.254 0.508)
			(end -0.254 0.508)
			(stroke
				(width 0.0254)
				(type default)
			)
			(layer "F.Fab")
		)
		(fp_line
			(start -0.254 -0.508)
			(end 0.254 -0.508)
			(stroke
				(width 0.0254)
				(type default)
			)
			(layer "F.Fab")
		)
		(fp_line
			(start 0.254 -0.508)
			(end 0.254 0.508)
			(stroke
				(width 0.0254)
				(type default)
			)
			(layer "F.Fab")
		)
		(pad "1" smd rect
			(at 0 -0.4191 270)
			(size 0.508 0.5334)
			(layers "F.Cu" "F.Mask" "F.Paste")
			(net "CORE_FB_ALERT_L")
		)
		(pad "2" smd rect
			(at 0 0.4191 270)
			(size 0.508 0.5334)
			(layers "F.Cu" "F.Mask" "F.Paste")
			(net "EXT_3.3V")
		)
		(zone
			(layer "F.Cu")
			(hatch none 0.5)
			(connect_pads
				(clearance 0)
			)
			(min_thickness 0.25)
			(keepout
				(tracks not_allowed)
				(vias allowed)
				(pads allowed)
				(copperpour not_allowed)
				(footprints allowed)
			)
			(placement
				(enabled no)
				(sheetname "")
			)
			(fill
				(thermal_gap 0.5)
				(thermal_bridge_width 0.5)
				(island_removal_mode 0)
			)
			(polygon
				(pts
					(xy 25.9842 35.9664) (xy 25.9334 35.9664) (xy 25.9334 35.9156) (xy 25.9842 35.9156)
				)
			)
		)
	)
	(footprint ""
		(layer "F.Cu")
		(at 32.258 43.942)
		(property "Reference" "R287"
			(at 0 0 0)
			(layer "F.SilkS")
			(hide yes)
			(effects
				(font
					(size 1.27 1.27)
				)
			)
		)
		(property "Value" "100"
			(at -0.148158 1.3462 90)
			(unlocked yes)
			(layer "F.Fab")
			(hide yes)
			(effects
				(font
					(size 1.27 0.9652)
					(thickness 0.000001)
				)
				(justify left)
			)
		)
		(property "Device Type" "REST4030"
			(at -0.148158 1.3462 90)
			(unlocked yes)
			(layer "F.Fab")
			(hide yes)
			(effects
				(font
					(size 1.27 0.9652)
					(thickness 0.000001)
				)
				(justify left)
			)
		)
		(duplicate_pad_numbers_are_jumpers no)
		(fp_poly
			(pts
				(xy 0.635 1.0668) (xy 0.635 -1.0668) (xy -0.635 -1.0668) (xy -0.635 1.0668)
			)
			(stroke
				(width 0)
				(type default)
			)
			(fill no)
			(layer "F.CrtYd")
		)
		(fp_line
			(start -0.254 -0.508)
			(end 0.254 -0.508)
			(stroke
				(width 0.0254)
				(type default)
			)
			(layer "F.Fab")
		)
		(fp_line
			(start -0.254 0.508)
			(end -0.254 -0.508)
			(stroke
				(width 0.0254)
				(type default)
			)
			(layer "F.Fab")
		)
		(fp_line
			(start 0.254 -0.508)
			(end 0.254 0.508)
			(stroke
				(width 0.0254)
				(type default)
			)
			(layer "F.Fab")
		)
		(fp_line
			(start 0.254 0.508)
			(end -0.254 0.508)
			(stroke
				(width 0.0254)
				(type default)
			)
			(layer "F.Fab")
		)
		(pad "1" smd rect
			(at 0 -0.4191)
			(size 0.508 0.5334)
			(layers "F.Cu" "F.Mask" "F.Paste")
			(net "10N2535")
		)
		(pad "2" smd rect
			(at 0 0.4191)
			(size 0.508 0.5334)
			(layers "F.Cu" "F.Mask" "F.Paste")
			(net "10N2410")
		)
		(zone
			(layer "F.Cu")
			(hatch none 0.5)
			(connect_pads
				(clearance 0)
			)
			(min_thickness 0.25)
			(keepout
				(tracks not_allowed)
				(vias allowed)
				(pads allowed)
				(copperpour not_allowed)
				(footprints allowed)
			)
			(placement
				(enabled no)
				(sheetname "")
			)
			(fill
				(thermal_gap 0.5)
				(thermal_bridge_width 0.5)
				(island_removal_mode 0)
			)
			(polygon
				(pts
					(xy 32.2834 43.9166) (xy 32.2834 43.9674) (xy 32.2326 43.9674) (xy 32.2326 43.9166)
				)
			)
		)
	)
	(footprint ""
		(layer "F.Cu")
		(at 14.351 1.397)
		(property "Reference" "R389"
			(at -0.86233 -1.016 90)
			(unlocked yes)
			(layer "F.SilkS")
			(effects
				(font
					(size 0.7874 0.5842)
					(thickness 0.127)
				)
				(justify left)
			)
		)
		(property "Value" "0"
			(at -0.148158 1.3462 90)
			(unlocked yes)
			(layer "F.Fab")
			(hide yes)
			(effects
				(font
					(size 1.27 0.9652)
					(thickness 0.000001)
				)
				(justify left)
			)
		)
		(property "Device Type" "REST1111"
			(at -0.148158 1.3462 90)
			(unlocked yes)
			(layer "F.Fab")
			(hide yes)
			(effects
				(font
					(size 1.27 0.9652)
					(thickness 0.000001)
				)
				(justify left)
			)
		)
		(duplicate_pad_numbers_are_jumpers no)
		(fp_poly
			(pts
				(xy 0.635 1.0668) (xy 0.635 -1.0668) (xy -0.635 -1.0668) (xy -0.635 1.0668)
			)
			(stroke
				(width 0)
				(type default)
			)
			(fill no)
			(layer "F.CrtYd")
		)
		(fp_line
			(start -0.254 -0.508)
			(end 0.254 -0.508)
			(stroke
				(width 0.0254)
				(type default)
			)
			(layer "F.Fab")
		)
		(fp_line
			(start -0.254 0.508)
			(end -0.254 -0.508)
			(stroke
				(width 0.0254)
				(type default)
			)
			(layer "F.Fab")
		)
		(fp_line
			(start 0.254 -0.508)
			(end 0.254 0.508)
			(stroke
				(width 0.0254)
				(type default)
			)
			(layer "F.Fab")
		)
		(fp_line
			(start 0.254 0.508)
			(end -0.254 0.508)
			(stroke
				(width 0.0254)
				(type default)
			)
			(layer "F.Fab")
		)
		(pad "1" smd rect
			(at 0 -0.4191)
			(size 0.508 0.5334)
			(layers "F.Cu" "F.Mask" "F.Paste")
			(net "NFP_SMBUS_SCL")
		)
		(pad "2" smd rect
			(at 0 0.4191)
			(size 0.508 0.5334)
			(layers "F.Cu" "F.Mask" "F.Paste")
			(net "SMBUS_SCL")
		)
		(zone
			(layer "F.Cu")
			(hatch none 0.5)
			(connect_pads
				(clearance 0)
			)
			(min_thickness 0.25)
			(keepout
				(tracks not_allowed)
				(vias allowed)
				(pads allowed)
				(copperpour not_allowed)
				(footprints allowed)
			)
			(placement
				(enabled no)
				(sheetname "")
			)
			(fill
				(thermal_gap 0.5)
				(thermal_bridge_width 0.5)
				(island_removal_mode 0)
			)
			(polygon
				(pts
					(xy 14.3764 1.3716) (xy 14.3764 1.4224) (xy 14.3256 1.4224) (xy 14.3256 1.3716)
				)
			)
		)
	)
	(footprint ""
		(layer "F.Cu")
		(at 26.543 46.99)
		(property "Reference" "TP59"
			(at 1.55067 2.54 90)
			(unlocked yes)
			(layer "F.SilkS")
			(effects
				(font
					(size 0.7874 0.5842)
					(thickness 0.127)
				)
				(justify left)
			)
		)
		(property "Value" "*"
			(at -0.4826 -0.14732 0)
			(unlocked yes)
			(layer "F.Fab")
			(hide yes)
			(effects
				(font
					(size 1.27 0.9652)
					(thickness 0.000001)
				)
				(justify left)
			)
		)
		(property "Device Type" "TP_SMALL"
			(at -0.4826 -0.14732 0)
			(unlocked yes)
			(layer "F.Fab")
			(hide yes)
			(effects
				(font
					(size 1.27 0.9652)
					(thickness 0.000001)
				)
				(justify left)
			)
		)
		(duplicate_pad_numbers_are_jumpers no)
		(fp_line
			(start -0.8636 -0.8636)
			(end -0.8636 0.8636)
			(stroke
				(width 0.1524)
				(type default)
			)
			(layer "F.SilkS")
		)
		(fp_line
			(start -0.8636 0.8636)
			(end 0.8636 0.8636)
			(stroke
				(width 0.1524)
				(type default)
			)
			(layer "F.SilkS")
		)
		(fp_line
			(start 0.8636 -0.8636)
			(end -0.8636 -0.8636)
			(stroke
				(width 0.1524)
				(type default)
			)
			(layer "F.SilkS")
		)
		(fp_line
			(start 0.8636 0.8636)
			(end 0.8636 -0.8636)
			(stroke
				(width 0.1524)
				(type default)
			)
			(layer "F.SilkS")
		)
		(fp_poly
			(pts
				(xy -0.635 -0.635) (xy -0.635 0.635) (xy 0.635 0.635) (xy 0.635 -0.635)
			)
			(stroke
				(width 0)
				(type default)
			)
			(fill no)
			(layer "F.CrtYd")
		)
		(pad "1" smd rect
			(at 0 0)
			(size 1.27 1.27)
			(layers "F.Cu" "F.Mask" "F.Paste")
			(net "VDD_CORE_PGOOD")
		)
	)
)
